(kicad_pcb
	(version 20260206)
	(generator "pcbnew")
	(generator_version "10.0")
	(general
		(thickness 1.6)
		(legacy_teardrops no)
	)
	(paper "A4")
	(title_block
		(title "01162023_DA0F0TEBIF0_F0T_Expander_BD_F_brd_V02_OCP.brd")
		(comment 1 "Grand Teton / footprints 2472-2478 of 9728")
	)
	(layers
		(0 "F.Cu" signal "TOP")
		(4 "In1.Cu" signal "GND")
		(6 "In2.Cu" signal "VCC")
		(8 "In3.Cu" signal "VCC1")
		(10 "In4.Cu" signal "GND1")
		(12 "In5.Cu" signal "IN1")
		(14 "In6.Cu" signal "GND2")
		(16 "In7.Cu" signal "IN2")
		(18 "In8.Cu" signal "GND3")
		(20 "In9.Cu" signal "IN3")
		(22 "In10.Cu" signal "GND4")
		(24 "In11.Cu" signal "IN4")
		(26 "In12.Cu" signal "GND5")
		(28 "In13.Cu" signal "IN5")
		(30 "In14.Cu" signal "GND6")
		(32 "In15.Cu" signal "IN6")
		(34 "In16.Cu" signal "GND7")
		(2 "B.Cu" signal "BOTTOM")
		(9 "F.Adhes" user "F.Adhesive")
		(11 "B.Adhes" user "B.Adhesive")
		(13 "F.Paste" user "Package Geometry/Pastemask Top")
		(15 "B.Paste" user "Package Geometry/Pastemask Bottom")
		(5 "F.SilkS" user "Ref Des/Silkscreen Top")
		(7 "B.SilkS" user "Ref Des/Silkscreen Bottom")
		(1 "F.Mask" user "Board Geometry/Soldermask Top")
		(3 "B.Mask" user "Board Geometry/Soldermask Bottom")
		(17 "Dwgs.User" user "User.Drawings")
		(19 "Cmts.User" user "User.Comments")
		(21 "Eco1.User" user "User.Eco1")
		(23 "Eco2.User" user "User.Eco2")
		(25 "Edge.Cuts" user "Board Geometry/Outline")
		(27 "Margin" user)
		(31 "F.CrtYd" user "Package Geometry/Place Bound Top")
		(29 "B.CrtYd" user "Package Geometry/Place Bound Bottom")
		(35 "F.Fab" user "Ref Des/Assembly Top")
		(33 "B.Fab" user "Ref Des/Assembly Bottom")
	)
	(footprint ""
		(layer "F.Cu")
		(at 279.730454 -66.32194 -90)
		(property "Reference" "PC867"
			(at 0 0 270)
			(layer "F.SilkS")
			(hide yes)
			(effects
				(font
					(size 1.27 1.27)
				)
			)
		)
		(property "Value" ""
			(at 0 0 270)
			(layer "F.Fab")
			(effects
				(font
					(size 1.27 1.27)
				)
			)
		)
		(duplicate_pad_numbers_are_jumpers no)
		(fp_line
			(start -0.7874 0.4064)
			(end -0.7874 -0.4064)
			(stroke
				(width 0.1524)
				(type default)
			)
			(layer "F.SilkS")
		)
		(fp_line
			(start 0.7874 0.4064)
			(end -0.7874 0.4064)
			(stroke
				(width 0.1524)
				(type default)
			)
			(layer "F.SilkS")
		)
		(fp_line
			(start -0.7874 -0.4064)
			(end 0.7874 -0.4064)
			(stroke
				(width 0.1524)
				(type default)
			)
			(layer "F.SilkS")
		)
		(fp_line
			(start 0.7874 -0.4064)
			(end 0.7874 0.4064)
			(stroke
				(width 0.1524)
				(type default)
			)
			(layer "F.SilkS")
		)
		(fp_line
			(start -0.67945 0.3048)
			(end -0.67945 -0.305054)
			(stroke
				(width 0.1)
				(type default)
			)
			(layer "F.Fab")
		)
		(fp_line
			(start -0.12065 0.3048)
			(end -0.67945 0.3048)
			(stroke
				(width 0.1)
				(type default)
			)
			(layer "F.Fab")
		)
		(fp_line
			(start 0.120396 0.3048)
			(end 0.120396 0.2794)
			(stroke
				(width 0.1)
				(type default)
			)
			(layer "F.Fab")
		)
		(fp_line
			(start 0.67945 0.3048)
			(end 0.120396 0.3048)
			(stroke
				(width 0.1)
				(type default)
			)
			(layer "F.Fab")
		)
		(fp_line
			(start -0.12065 0.2794)
			(end -0.12065 0.3048)
			(stroke
				(width 0.1)
				(type default)
			)
			(layer "F.Fab")
		)
		(fp_line
			(start 0.120396 0.2794)
			(end -0.12065 0.2794)
			(stroke
				(width 0.1)
				(type default)
			)
			(layer "F.Fab")
		)
		(fp_line
			(start -0.12065 -0.2794)
			(end 0.12065 -0.2794)
			(stroke
				(width 0.1)
				(type default)
			)
			(layer "F.Fab")
		)
		(fp_line
			(start 0.12065 -0.2794)
			(end 0.12065 -0.3048)
			(stroke
				(width 0.1)
				(type default)
			)
			(layer "F.Fab")
		)
		(fp_line
			(start 0.12065 -0.3048)
			(end 0.67945 -0.3048)
			(stroke
				(width 0.1)
				(type default)
			)
			(layer "F.Fab")
		)
		(fp_line
			(start 0.67945 -0.3048)
			(end 0.67945 0.3048)
			(stroke
				(width 0.1)
				(type default)
			)
			(layer "F.Fab")
		)
		(fp_line
			(start -0.67945 -0.305054)
			(end -0.12065 -0.305054)
			(stroke
				(width 0.1)
				(type default)
			)
			(layer "F.Fab")
		)
		(fp_line
			(start -0.12065 -0.305054)
			(end -0.12065 -0.2794)
			(stroke
				(width 0.1)
				(type default)
			)
			(layer "F.Fab")
		)
		(pad "1" smd circle
			(at -0.40005 0 270)
			(size 0 0)
			(layers "F.Cu" "F.Mask" "F.Paste")
			(net "P12V_SSD9_CO_DV_DT")
		)
		(pad "2" smd circle
			(at 0.40005 0 270)
			(size 0 0)
			(layers "F.Cu" "F.Mask" "F.Paste")
			(net "GND")
		)
	)
	(footprint ""
		(layer "F.Cu")
		(at 112.85728 -313.620404)
		(property "Reference" "L49"
			(at 3.58267 1.35636 90)
			(unlocked yes)
			(layer "F.SilkS")
			(effects
				(font
					(size 0.7874 0.5842)
					(thickness 0.1524)
				)
				(justify left)
			)
		)
		(property "Value" ""
			(at 0 0 0)
			(layer "F.Fab")
			(effects
				(font
					(size 1.27 1.27)
				)
			)
		)
		(duplicate_pad_numbers_are_jumpers no)
		(fp_line
			(start -2.248154 -4.9911)
			(end -2.248154 -1.54559)
			(stroke
				(width 0.1524)
				(type default)
			)
			(layer "F.SilkS")
		)
		(fp_line
			(start -2.248154 1.572768)
			(end -2.248154 4.9911)
			(stroke
				(width 0.1524)
				(type default)
			)
			(layer "F.SilkS")
		)
		(fp_line
			(start -2.248154 4.9911)
			(end 2.248154 4.9911)
			(stroke
				(width 0.1524)
				(type default)
			)
			(layer "F.SilkS")
		)
		(fp_line
			(start 2.248154 -4.9911)
			(end -2.248154 -4.9911)
			(stroke
				(width 0.1524)
				(type default)
			)
			(layer "F.SilkS")
		)
		(fp_line
			(start 2.248154 -1.501648)
			(end 2.248154 -4.9911)
			(stroke
				(width 0.1524)
				(type default)
			)
			(layer "F.SilkS")
		)
		(fp_line
			(start 2.248154 4.9911)
			(end 2.248154 1.605788)
			(stroke
				(width 0.1524)
				(type default)
			)
			(layer "F.SilkS")
		)
		(fp_line
			(start -1.700022 -0.899922)
			(end -1.700022 0.899922)
			(stroke
				(width 0.1)
				(type default)
			)
			(layer "F.Fab")
		)
		(fp_line
			(start -1.700022 0.899922)
			(end 1.700022 0.899922)
			(stroke
				(width 0.1)
				(type default)
			)
			(layer "F.Fab")
		)
		(fp_line
			(start 1.700022 -0.899922)
			(end -1.700022 -0.899922)
			(stroke
				(width 0.1)
				(type default)
			)
			(layer "F.Fab")
		)
		(fp_line
			(start 1.700022 0.899922)
			(end 1.700022 -0.899922)
			(stroke
				(width 0.1)
				(type default)
			)
			(layer "F.Fab")
		)
		(pad "1" smd rect
			(at -1.575054 0)
			(size 1.1684 9.8044)
			(layers "F.Cu" "F.Mask" "F.Paste")
			(net "P0V8_PEX0")
		)
		(pad "2" smd rect
			(at 1.575054 0)
			(size 1.1684 9.8044)
			(layers "F.Cu" "F.Mask" "F.Paste")
			(net "P0V8_SERDES_VDDA_PEX0")
		)
	)
	(footprint ""
		(layer "F.Cu")
		(at 135.96239 -184.656984 -90)
		(property "Reference" "R1110"
			(at 0 0 270)
			(layer "F.SilkS")
			(hide yes)
			(effects
				(font
					(size 1.27 1.27)
				)
			)
		)
		(property "Value" ""
			(at 0 0 270)
			(layer "F.Fab")
			(effects
				(font
					(size 1.27 1.27)
				)
			)
		)
		(duplicate_pad_numbers_are_jumpers no)
		(fp_line
			(start 0.7874 0.4064)
			(end -0.7874 0.4064)
			(stroke
				(width 0.1524)
				(type default)
			)
			(layer "F.SilkS")
		)
		(fp_line
			(start -0.67945 0.3048)
			(end -0.67945 -0.305054)
			(stroke
				(width 0.1)
				(type default)
			)
			(layer "F.Fab")
		)
		(fp_line
			(start -0.12065 0.3048)
			(end -0.67945 0.3048)
			(stroke
				(width 0.1)
				(type default)
			)
			(layer "F.Fab")
		)
		(fp_line
			(start 0.120396 0.3048)
			(end 0.120396 0.2794)
			(stroke
				(width 0.1)
				(type default)
			)
			(layer "F.Fab")
		)
		(fp_line
			(start 0.67945 0.3048)
			(end 0.120396 0.3048)
			(stroke
				(width 0.1)
				(type default)
			)
			(layer "F.Fab")
		)
		(fp_line
			(start -0.12065 0.2794)
			(end -0.12065 0.3048)
			(stroke
				(width 0.1)
				(type default)
			)
			(layer "F.Fab")
		)
		(fp_line
			(start 0.120396 0.2794)
			(end -0.12065 0.2794)
			(stroke
				(width 0.1)
				(type default)
			)
			(layer "F.Fab")
		)
		(fp_line
			(start -0.12065 -0.2794)
			(end 0.12065 -0.2794)
			(stroke
				(width 0.1)
				(type default)
			)
			(layer "F.Fab")
		)
		(fp_line
			(start 0.12065 -0.2794)
			(end 0.12065 -0.3048)
			(stroke
				(width 0.1)
				(type default)
			)
			(layer "F.Fab")
		)
		(fp_line
			(start 0.12065 -0.3048)
			(end 0.67945 -0.3048)
			(stroke
				(width 0.1)
				(type default)
			)
			(layer "F.Fab")
		)
		(fp_line
			(start 0.67945 -0.3048)
			(end 0.67945 0.3048)
			(stroke
				(width 0.1)
				(type default)
			)
			(layer "F.Fab")
		)
		(fp_line
			(start -0.67945 -0.305054)
			(end -0.12065 -0.305054)
			(stroke
				(width 0.1)
				(type default)
			)
			(layer "F.Fab")
		)
		(fp_line
			(start -0.12065 -0.305054)
			(end -0.12065 -0.2794)
			(stroke
				(width 0.1)
				(type default)
			)
			(layer "F.Fab")
		)
		(pad "1" smd circle
			(at -0.40005 0 270)
			(size 0 0)
			(layers "F.Cu" "F.Mask" "F.Paste")
			(net "CLK_100M_DB2000QL_NIC7_R_DN")
		)
		(pad "2" smd circle
			(at 0.40005 0 270)
			(size 0 0)
			(layers "F.Cu" "F.Mask" "F.Paste")
			(net "CLK_100M_DB2000QL_NIC7_DN")
		)
	)
	(footprint ""
		(layer "F.Cu")
		(at 110.152942 -116.230654 90)
		(property "Reference" "PR6873"
			(at 0 0 90)
			(layer "F.SilkS")
			(hide yes)
			(effects
				(font
					(size 1.27 1.27)
				)
			)
		)
		(property "Value" ""
			(at 0 0 90)
			(layer "F.Fab")
			(effects
				(font
					(size 1.27 1.27)
				)
			)
		)
		(duplicate_pad_numbers_are_jumpers no)
		(fp_line
			(start 0.7874 -0.4064)
			(end 0.7874 0.4064)
			(stroke
				(width 0.1524)
				(type default)
			)
			(layer "F.SilkS")
		)
		(fp_line
			(start -0.7874 -0.4064)
			(end 0.7874 -0.4064)
			(stroke
				(width 0.1524)
				(type default)
			)
			(layer "F.SilkS")
		)
		(fp_line
			(start 0.7874 0.4064)
			(end -0.7874 0.4064)
			(stroke
				(width 0.1524)
				(type default)
			)
			(layer "F.SilkS")
		)
		(fp_line
			(start -0.7874 0.4064)
			(end -0.7874 -0.4064)
			(stroke
				(width 0.1524)
				(type default)
			)
			(layer "F.SilkS")
		)
		(fp_line
			(start -0.12065 -0.305054)
			(end -0.12065 -0.2794)
			(stroke
				(width 0.1)
				(type default)
			)
			(layer "F.Fab")
		)
		(fp_line
			(start -0.67945 -0.305054)
			(end -0.12065 -0.305054)
			(stroke
				(width 0.1)
				(type default)
			)
			(layer "F.Fab")
		)
		(fp_line
			(start 0.67945 -0.3048)
			(end 0.67945 0.3048)
			(stroke
				(width 0.1)
				(type default)
			)
			(layer "F.Fab")
		)
		(fp_line
			(start 0.12065 -0.3048)
			(end 0.67945 -0.3048)
			(stroke
				(width 0.1)
				(type default)
			)
			(layer "F.Fab")
		)
		(fp_line
			(start 0.12065 -0.2794)
			(end 0.12065 -0.3048)
			(stroke
				(width 0.1)
				(type default)
			)
			(layer "F.Fab")
		)
		(fp_line
			(start -0.12065 -0.2794)
			(end 0.12065 -0.2794)
			(stroke
				(width 0.1)
				(type default)
			)
			(layer "F.Fab")
		)
		(fp_line
			(start 0.120396 0.2794)
			(end -0.12065 0.2794)
			(stroke
				(width 0.1)
				(type default)
			)
			(layer "F.Fab")
		)
		(fp_line
			(start -0.12065 0.2794)
			(end -0.12065 0.3048)
			(stroke
				(width 0.1)
				(type default)
			)
			(layer "F.Fab")
		)
		(fp_line
			(start 0.67945 0.3048)
			(end 0.120396 0.3048)
			(stroke
				(width 0.1)
				(type default)
			)
			(layer "F.Fab")
		)
		(fp_line
			(start 0.120396 0.3048)
			(end 0.120396 0.2794)
			(stroke
				(width 0.1)
				(type default)
			)
			(layer "F.Fab")
		)
		(fp_line
			(start -0.12065 0.3048)
			(end -0.67945 0.3048)
			(stroke
				(width 0.1)
				(type default)
			)
			(layer "F.Fab")
		)
		(fp_line
			(start -0.67945 0.3048)
			(end -0.67945 -0.305054)
			(stroke
				(width 0.1)
				(type default)
			)
			(layer "F.Fab")
		)
		(pad "1" smd circle
			(at -0.40005 0 90)
			(size 0 0)
			(layers "F.Cu" "F.Mask" "F.Paste")
			(net "P12V_NIC1_CO_FLTB")
		)
		(pad "2" smd circle
			(at 0.40005 0 90)
			(size 0 0)
			(layers "F.Cu" "F.Mask" "F.Paste")
			(net "P3V3_AUX")
		)
	)
	(footprint ""
		(layer "F.Cu")
		(at 355.854 -167.64 180)
		(property "Reference" "R4735"
			(at 0 0 180)
			(layer "F.SilkS")
			(hide yes)
			(effects
				(font
					(size 1.27 1.27)
				)
			)
		)
		(property "Value" ""
			(at 0 0 180)
			(layer "F.Fab")
			(effects
				(font
					(size 1.27 1.27)
				)
			)
		)
		(duplicate_pad_numbers_are_jumpers no)
		(fp_line
			(start 0.7874 0.4064)
			(end -0.7874 0.4064)
			(stroke
				(width 0.1524)
				(type default)
			)
			(layer "F.SilkS")
		)
		(fp_line
			(start 0.7874 -0.4064)
			(end 0.7874 0.4064)
			(stroke
				(width 0.1524)
				(type default)
			)
			(layer "F.SilkS")
		)
		(fp_line
			(start -0.7874 0.4064)
			(end -0.7874 -0.4064)
			(stroke
				(width 0.1524)
				(type default)
			)
			(layer "F.SilkS")
		)
		(fp_line
			(start -0.7874 -0.4064)
			(end 0.7874 -0.4064)
			(stroke
				(width 0.1524)
				(type default)
			)
			(layer "F.SilkS")
		)
		(fp_line
			(start 0.67945 0.3048)
			(end 0.120396 0.3048)
			(stroke
				(width 0.1)
				(type default)
			)
			(layer "F.Fab")
		)
		(fp_line
			(start 0.67945 -0.3048)
			(end 0.67945 0.3048)
			(stroke
				(width 0.1)
				(type default)
			)
			(layer "F.Fab")
		)
		(fp_line
			(start 0.12065 -0.2794)
			(end 0.12065 -0.3048)
			(stroke
				(width 0.1)
				(type default)
			)
			(layer "F.Fab")
		)
		(fp_line
			(start 0.12065 -0.3048)
			(end 0.67945 -0.3048)
			(stroke
				(width 0.1)
				(type default)
			)
			(layer "F.Fab")
		)
		(fp_line
			(start 0.120396 0.3048)
			(end 0.120396 0.2794)
			(stroke
				(width 0.1)
				(type default)
			)
			(layer "F.Fab")
		)
		(fp_line
			(start 0.120396 0.2794)
			(end -0.12065 0.2794)
			(stroke
				(width 0.1)
				(type default)
			)
			(layer "F.Fab")
		)
		(fp_line
			(start -0.12065 0.3048)
			(end -0.67945 0.3048)
			(stroke
				(width 0.1)
				(type default)
			)
			(layer "F.Fab")
		)
		(fp_line
			(start -0.12065 0.2794)
			(end -0.12065 0.3048)
			(stroke
				(width 0.1)
				(type default)
			)
			(layer "F.Fab")
		)
		(fp_line
			(start -0.12065 -0.2794)
			(end 0.12065 -0.2794)
			(stroke
				(width 0.1)
				(type default)
			)
			(layer "F.Fab")
		)
		(fp_line
			(start -0.12065 -0.305054)
			(end -0.12065 -0.2794)
			(stroke
				(width 0.1)
				(type default)
			)
			(layer "F.Fab")
		)
		(fp_line
			(start -0.67945 0.3048)
			(end -0.67945 -0.305054)
			(stroke
				(width 0.1)
				(type default)
			)
			(layer "F.Fab")
		)
		(fp_line
			(start -0.67945 -0.305054)
			(end -0.12065 -0.305054)
			(stroke
				(width 0.1)
				(type default)
			)
			(layer "F.Fab")
		)
		(pad "1" smd circle
			(at -0.40005 0 180)
			(size 0 0)
			(layers "F.Cu" "F.Mask" "F.Paste")
			(net "P3V3_AUX")
		)
		(pad "2" smd circle
			(at 0.40005 0 180)
			(size 0 0)
			(layers "F.Cu" "F.Mask" "F.Paste")
			(net "RST_PEX_NIC5_PERST_R_N")
		)
	)
	(footprint ""
		(layer "F.Cu")
		(at 34.179002 -59.577986 -90)
		(property "Reference" "R888"
			(at 0 0 270)
			(layer "F.SilkS")
			(hide yes)
			(effects
				(font
					(size 1.27 1.27)
				)
			)
		)
		(property "Value" ""
			(at 0 0 270)
			(layer "F.Fab")
			(effects
				(font
					(size 1.27 1.27)
				)
			)
		)
		(duplicate_pad_numbers_are_jumpers no)
		(fp_line
			(start -0.7874 0.4064)
			(end -0.7874 -0.4064)
			(stroke
				(width 0.1524)
				(type default)
			)
			(layer "F.SilkS")
		)
		(fp_line
			(start 0.7874 0.4064)
			(end -0.7874 0.4064)
			(stroke
				(width 0.1524)
				(type default)
			)
			(layer "F.SilkS")
		)
		(fp_line
			(start -0.7874 -0.4064)
			(end 0.7874 -0.4064)
			(stroke
				(width 0.1524)
				(type default)
			)
			(layer "F.SilkS")
		)
		(fp_line
			(start 0.7874 -0.4064)
			(end 0.7874 0.4064)
			(stroke
				(width 0.1524)
				(type default)
			)
			(layer "F.SilkS")
		)
		(fp_line
			(start -0.67945 0.3048)
			(end -0.67945 -0.305054)
			(stroke
				(width 0.1)
				(type default)
			)
			(layer "F.Fab")
		)
		(fp_line
			(start -0.12065 0.3048)
			(end -0.67945 0.3048)
			(stroke
				(width 0.1)
				(type default)
			)
			(layer "F.Fab")
		)
		(fp_line
			(start 0.120396 0.3048)
			(end 0.120396 0.2794)
			(stroke
				(width 0.1)
				(type default)
			)
			(layer "F.Fab")
		)
		(fp_line
			(start 0.67945 0.3048)
			(end 0.120396 0.3048)
			(stroke
				(width 0.1)
				(type default)
			)
			(layer "F.Fab")
		)
		(fp_line
			(start -0.12065 0.2794)
			(end -0.12065 0.3048)
			(stroke
				(width 0.1)
				(type default)
			)
			(layer "F.Fab")
		)
		(fp_line
			(start 0.120396 0.2794)
			(end -0.12065 0.2794)
			(stroke
				(width 0.1)
				(type default)
			)
			(layer "F.Fab")
		)
		(fp_line
			(start -0.12065 -0.2794)
			(end 0.12065 -0.2794)
			(stroke
				(width 0.1)
				(type default)
			)
			(layer "F.Fab")
		)
		(fp_line
			(start 0.12065 -0.2794)
			(end 0.12065 -0.3048)
			(stroke
				(width 0.1)
				(type default)
			)
			(layer "F.Fab")
		)
		(fp_line
			(start 0.12065 -0.3048)
			(end 0.67945 -0.3048)
			(stroke
				(width 0.1)
				(type default)
			)
			(layer "F.Fab")
		)
		(fp_line
			(start 0.67945 -0.3048)
			(end 0.67945 0.3048)
			(stroke
				(width 0.1)
				(type default)
			)
			(layer "F.Fab")
		)
		(fp_line
			(start -0.67945 -0.305054)
			(end -0.12065 -0.305054)
			(stroke
				(width 0.1)
				(type default)
			)
			(layer "F.Fab")
		)
		(fp_line
			(start -0.12065 -0.305054)
			(end -0.12065 -0.2794)
			(stroke
				(width 0.1)
				(type default)
			)
			(layer "F.Fab")
		)
		(pad "1" smd circle
			(at -0.40005 0 270)
			(size 0 0)
			(layers "F.Cu" "F.Mask" "F.Paste")
			(net "P3V3_SSD1")
		)
		(pad "2" smd circle
			(at 0.40005 0 270)
			(size 0 0)
			(layers "F.Cu" "F.Mask" "F.Paste")
			(net "PWRGD_P3V3_SSD1")
		)
	)
	(footprint ""
		(layer "F.Cu")
		(at 131.404868 -356.244906 90)
		(property "Reference" "C2256"
			(at 0 0 90)
			(layer "F.SilkS")
			(hide yes)
			(effects
				(font
					(size 1.27 1.27)
				)
			)
		)
		(property "Value" ""
			(at 0 0 90)
			(layer "F.Fab")
			(effects
				(font
					(size 1.27 1.27)
				)
			)
		)
		(duplicate_pad_numbers_are_jumpers no)
		(fp_line
			(start 0.299974 -0.150114)
			(end 0.299974 0.150114)
			(stroke
				(width 0.1)
				(type default)
			)
			(layer "F.Fab")
		)
		(fp_line
			(start -0.299974 -0.150114)
			(end 0.299974 -0.150114)
			(stroke
				(width 0.1)
				(type default)
			)
			(layer "F.Fab")
		)
		(fp_line
			(start 0.299974 0.150114)
			(end -0.299974 0.150114)
			(stroke
				(width 0.1)
				(type default)
			)
			(layer "F.Fab")
		)
		(fp_line
			(start -0.299974 0.150114)
			(end -0.299974 -0.150114)
			(stroke
				(width 0.1)
				(type default)
			)
			(layer "F.Fab")
		)
		(pad "1" smd rect
			(at -0.2667 0 90)
			(size 0.3048 0.381)
			(layers "F.Cu" "F.Mask" "F.Paste")
			(net "P5E_PEX1_STN5_TX_DN<89>")
		)
		(pad "2" smd rect
			(at 0.2667 0 90)
			(size 0.3048 0.381)
			(layers "F.Cu" "F.Mask" "F.Paste")
			(net "P5E_PEX1_STN5_TX_C_DN<89>")
		)
	)
)
